(kicad_pcb
	(version 20260206)
	(generator "pcbnew")
	(generator_version "10.0")
	(general
		(thickness 1.6)
		(legacy_teardrops no)
	)
	(paper "A4")
	(title_block
		(title "Bryce Canyon_F.DPB_16315-1-OCP.brd")
		(comment 1 "Bryce Canyon / footprints 887-893 of 2223")
	)
	(layers
		(0 "F.Cu" signal "TOP")
		(4 "In1.Cu" signal "L2GND")
		(6 "In2.Cu" signal "L3")
		(8 "In3.Cu" signal "L4GND")
		(10 "In4.Cu" signal "L5")
		(12 "In5.Cu" signal "L6VCC")
		(14 "In6.Cu" signal "L7VCC")
		(16 "In7.Cu" signal "L8")
		(18 "In8.Cu" signal "L9GND")
		(20 "In9.Cu" signal "L10")
		(22 "In10.Cu" signal "L11GND")
		(2 "B.Cu" signal "BOTTOM")
		(9 "F.Adhes" user "F.Adhesive")
		(11 "B.Adhes" user "B.Adhesive")
		(13 "F.Paste" user "Package Geometry/Pastemask Top")
		(15 "B.Paste" user "Package Geometry/Pastemask Bottom")
		(5 "F.SilkS" user "Ref Des/Silkscreen Top")
		(7 "B.SilkS" user "Ref Des/Silkscreen Bottom")
		(1 "F.Mask" user "Board Geometry/Soldermask Top")
		(3 "B.Mask" user "Board Geometry/Soldermask Bottom")
		(17 "Dwgs.User" user "User.Drawings")
		(19 "Cmts.User" user "User.Comments")
		(21 "Eco1.User" user "User.Eco1")
		(23 "Eco2.User" user "User.Eco2")
		(25 "Edge.Cuts" user "Board Geometry/Outline")
		(27 "Margin" user)
		(31 "F.CrtYd" user "Package Geometry/Place Bound Top")
		(29 "B.CrtYd" user "Package Geometry/Place Bound Bottom")
		(35 "F.Fab" user "Ref Des/Assembly Top")
		(33 "B.Fab" user "Ref Des/Assembly Bottom")
	)
	(footprint ""
		(layer "F.Cu")
		(at 237.47984 -240.14303)
		(property "Reference" "Q16"
			(at 0 0 0)
			(layer "F.SilkS")
			(hide yes)
			(effects
				(font
					(size 1.27 1.27)
				)
			)
		)
		(property "Value" "SSM3K324R-GP"
			(at 0.127 -8.9662 0)
			(unlocked yes)
			(layer "F.Fab")
			(hide yes)
			(effects
				(font
					(size 1.016 1.016)
					(thickness 0.1524)
				)
			)
		)
		(property "Device Type" "SOT23DGS2D4H35"
			(at 0.127 -10.4902 0)
			(unlocked yes)
			(layer "F.Fab")
			(hide yes)
			(effects
				(font
					(size 1.016 1.016)
					(thickness 0.1524)
				)
			)
		)
		(duplicate_pad_numbers_are_jumpers no)
		(fp_line
			(start -1.651 -1.778)
			(end -1.651 1.778)
			(stroke
				(width 0.1524)
				(type default)
			)
			(layer "F.SilkS")
		)
		(fp_line
			(start -1.651 1.778)
			(end 1.651 1.778)
			(stroke
				(width 0.1524)
				(type default)
			)
			(layer "F.SilkS")
		)
		(fp_line
			(start 1.651 -1.778)
			(end -1.651 -1.778)
			(stroke
				(width 0.1524)
				(type default)
			)
			(layer "F.SilkS")
		)
		(fp_line
			(start 1.651 1.778)
			(end 1.651 -1.778)
			(stroke
				(width 0.1524)
				(type default)
			)
			(layer "F.SilkS")
		)
		(fp_poly
			(pts
				(xy -1.778 1.8796) (xy -1.778 -1.8796) (xy 1.778 -1.8796) (xy 1.778 1.8796)
			)
			(stroke
				(width 0)
				(type default)
			)
			(fill no)
			(layer "F.CrtYd")
		)
		(fp_poly
			(pts
				(xy -1.778 1.8796) (xy -1.778 -1.8796) (xy 1.778 -1.8796) (xy 1.778 1.8796)
			)
			(stroke
				(width 0)
				(type default)
			)
			(fill no)
			(layer "F.Fab")
		)
		(pad "D" smd custom
			(at 0 -0.9525)
			(size 0.1905 0.1905)
			(layers "F.Cu" "F.Mask" "F.Paste")
			(net "P3V3_STBY_A")
			(options
				(clearance outline)
				(anchor circle)
			)
			(primitives
				(gr_poly
					(pts
						(arc
							(start -0.1778 0.5715)
							(mid -0.321484 0.511984)
							(end -0.381 0.3683)
						)
						(arc
							(start -0.381 -0.3683)
							(mid -0.321484 -0.511984)
							(end -0.1778 -0.5715)
						)
						(arc
							(start 0.1778 -0.5715)
							(mid 0.321484 -0.511984)
							(end 0.381 -0.3683)
						)
						(arc
							(start 0.381 0.3683)
							(mid 0.321484 0.511984)
							(end 0.1778 0.5715)
						)
					)
					(width 0)
					(fill yes)
				)
			)
		)
		(pad "G" smd custom
			(at -0.98425 0.9525)
			(size 0.1905 0.1905)
			(layers "F.Cu" "F.Mask" "F.Paste")
			(net "SCC_FULL_PWR_EN_5V")
			(options
				(clearance outline)
				(anchor circle)
			)
			(primitives
				(gr_poly
					(pts
						(arc
							(start -0.1778 0.5715)
							(mid -0.321484 0.511984)
							(end -0.381 0.3683)
						)
						(arc
							(start -0.381 -0.3683)
							(mid -0.321484 -0.511984)
							(end -0.1778 -0.5715)
						)
						(arc
							(start 0.1778 -0.5715)
							(mid 0.321484 -0.511984)
							(end 0.381 -0.3683)
						)
						(arc
							(start 0.381 0.3683)
							(mid 0.321484 0.511984)
							(end 0.1778 0.5715)
						)
					)
					(width 0)
					(fill yes)
				)
			)
		)
		(pad "S" smd custom
			(at 0.98425 0.9525)
			(size 0.1905 0.1905)
			(layers "F.Cu" "F.Mask" "F.Paste")
			(net "GPIO_VCC_U8")
			(options
				(clearance outline)
				(anchor circle)
			)
			(primitives
				(gr_poly
					(pts
						(arc
							(start -0.1778 0.5715)
							(mid -0.321484 0.511984)
							(end -0.381 0.3683)
						)
						(arc
							(start -0.381 -0.3683)
							(mid -0.321484 -0.511984)
							(end -0.1778 -0.5715)
						)
						(arc
							(start 0.1778 -0.5715)
							(mid 0.321484 -0.511984)
							(end 0.381 -0.3683)
						)
						(arc
							(start 0.381 0.3683)
							(mid 0.321484 0.511984)
							(end 0.1778 0.5715)
						)
					)
					(width 0)
					(fill yes)
				)
			)
		)
	)
	(footprint ""
		(layer "F.Cu")
		(at 140.915898 -64.683894 -90)
		(property "Reference" "C408"
			(at 0 0 270)
			(layer "F.SilkS")
			(hide yes)
			(effects
				(font
					(size 1.27 1.27)
				)
			)
		)
		(property "Value" "SC4D7U25V5KX-1-GP"
			(at -0.0762 -6.1214 270)
			(unlocked yes)
			(layer "F.Fab")
			(hide yes)
			(effects
				(font
					(size 1.016 1.016)
					(thickness 0.1524)
				)
			)
		)
		(property "Device Type" "C805H58"
			(at -0.0762 -8.1534 270)
			(unlocked yes)
			(layer "F.Fab")
			(hide yes)
			(effects
				(font
					(size 1.016 1.016)
					(thickness 0.1524)
				)
			)
		)
		(duplicate_pad_numbers_are_jumpers no)
		(fp_line
			(start 0.635 0)
			(end -0.635 0)
			(stroke
				(width 0.508)
				(type default)
			)
			(layer "F.SilkS")
		)
		(fp_rect
			(start -0.9652 1.778)
			(end 0.9652 -1.778)
			(stroke
				(width 0)
				(type default)
			)
			(fill no)
			(layer "F.CrtYd")
		)
		(fp_poly
			(pts
				(xy -0.9652 -1.778) (xy 0.9652 -1.778) (xy 0.9652 1.778) (xy -0.9652 1.778)
			)
			(stroke
				(width 0)
				(type default)
			)
			(fill no)
			(layer "F.Fab")
		)
		(pad "1" smd rect
			(at 0 -0.9652 270)
			(size 1.397 1.143)
			(layers "F.Cu" "F.Mask" "F.Paste")
			(net "P12V_HDD28")
		)
		(pad "2" smd rect
			(at 0 0.9652 270)
			(size 1.397 1.143)
			(layers "F.Cu" "F.Mask" "F.Paste")
			(net "GND")
		)
	)
	(footprint ""
		(layer "F.Cu")
		(at 230.7844 -384.2004 -90)
		(property "Reference" "R1145"
			(at 0 0 270)
			(layer "F.SilkS")
			(hide yes)
			(effects
				(font
					(size 1.27 1.27)
				)
			)
		)
		(property "Value" "0R2J-2-GP"
			(at 0.064008 -3.993896 270)
			(unlocked yes)
			(layer "F.Fab")
			(hide yes)
			(effects
				(font
					(size 1.016 1.016)
					(thickness 0.1524)
				)
			)
		)
		(property "Device Type" "R402H16"
			(at 0.064008 -5.517896 270)
			(unlocked yes)
			(layer "F.Fab")
			(hide yes)
			(effects
				(font
					(size 1.016 1.016)
					(thickness 0.1524)
				)
			)
		)
		(duplicate_pad_numbers_are_jumpers no)
		(fp_line
			(start -0.508 -0.9398)
			(end -0.508 0.9398)
			(stroke
				(width 0.1524)
				(type default)
			)
			(layer "F.SilkS")
		)
		(fp_line
			(start 0.508 -0.9398)
			(end -0.508 -0.9398)
			(stroke
				(width 0.1524)
				(type default)
			)
			(layer "F.SilkS")
		)
		(fp_rect
			(start -0.508 0.9398)
			(end 0.508 -0.9398)
			(stroke
				(width 0)
				(type default)
			)
			(fill no)
			(layer "F.CrtYd")
		)
		(fp_rect
			(start -0.508 0.9398)
			(end 0.508 -0.9398)
			(stroke
				(width 0)
				(type default)
			)
			(fill no)
			(layer "F.Fab")
		)
		(pad "1" smd custom
			(at 0 -0.4445 270)
			(size 0.1397 0.1397)
			(layers "F.Cu" "F.Mask" "F.Paste")
			(net "MB3_SDA_R")
			(options
				(clearance outline)
				(anchor circle)
			)
			(primitives
				(gr_poly
					(pts
						(arc
							(start -0.1778 -0.2794)
							(mid -0.249642 -0.249642)
							(end -0.2794 -0.1778)
						)
						(arc
							(start -0.2794 0.1778)
							(mid -0.249642 0.249642)
							(end -0.1778 0.2794)
						)
						(arc
							(start 0.1778 0.2794)
							(mid 0.249642 0.249642)
							(end 0.2794 0.1778)
						)
						(arc
							(start 0.2794 -0.1778)
							(mid 0.249642 -0.249642)
							(end 0.1778 -0.2794)
						)
					)
					(width 0)
					(fill yes)
				)
			)
		)
		(pad "2" smd custom
			(at 0 0.4445 270)
			(size 0.1397 0.1397)
			(layers "F.Cu" "F.Mask" "F.Paste")
			(net "I2C_DPB_A_SDA_BUF")
			(options
				(clearance outline)
				(anchor circle)
			)
			(primitives
				(gr_poly
					(pts
						(arc
							(start -0.1778 -0.2794)
							(mid -0.249642 -0.249642)
							(end -0.2794 -0.1778)
						)
						(arc
							(start -0.2794 0.1778)
							(mid -0.249642 0.249642)
							(end -0.1778 0.2794)
						)
						(arc
							(start 0.1778 0.2794)
							(mid 0.249642 0.249642)
							(end 0.2794 0.1778)
						)
						(arc
							(start 0.2794 -0.1778)
							(mid 0.249642 -0.249642)
							(end 0.1778 -0.2794)
						)
					)
					(width 0)
					(fill yes)
				)
			)
		)
	)
	(footprint ""
		(layer "F.Cu")
		(at 78.298548 -162.183318 180)
		(property "Reference" "R468"
			(at 0 0 180)
			(layer "F.SilkS")
			(hide yes)
			(effects
				(font
					(size 1.27 1.27)
				)
			)
		)
		(property "Value" "200KR2F-L-GP"
			(at 0.064008 -3.993896 180)
			(unlocked yes)
			(layer "F.Fab")
			(hide yes)
			(effects
				(font
					(size 1.016 1.016)
					(thickness 0.1524)
				)
			)
		)
		(property "Device Type" "R402H16"
			(at 0.064008 -5.517896 180)
			(unlocked yes)
			(layer "F.Fab")
			(hide yes)
			(effects
				(font
					(size 1.016 1.016)
					(thickness 0.1524)
				)
			)
		)
		(duplicate_pad_numbers_are_jumpers no)
		(fp_line
			(start 0.508 -0.9398)
			(end -0.508 -0.9398)
			(stroke
				(width 0.1524)
				(type default)
			)
			(layer "F.SilkS")
		)
		(fp_line
			(start -0.508 -0.9398)
			(end -0.508 0.9398)
			(stroke
				(width 0.1524)
				(type default)
			)
			(layer "F.SilkS")
		)
		(fp_rect
			(start -0.508 0.9398)
			(end 0.508 -0.9398)
			(stroke
				(width 0)
				(type default)
			)
			(fill no)
			(layer "F.CrtYd")
		)
		(fp_rect
			(start -0.508 0.9398)
			(end 0.508 -0.9398)
			(stroke
				(width 0)
				(type default)
			)
			(fill no)
			(layer "F.Fab")
		)
		(pad "1" smd custom
			(at 0 -0.4445 180)
			(size 0.1397 0.1397)
			(layers "F.Cu" "F.Mask" "F.Paste")
			(net "SW_HDD_R14")
			(options
				(clearance outline)
				(anchor circle)
			)
			(primitives
				(gr_poly
					(pts
						(arc
							(start -0.1778 -0.2794)
							(mid -0.249642 -0.249642)
							(end -0.2794 -0.1778)
						)
						(arc
							(start -0.2794 0.1778)
							(mid -0.249642 0.249642)
							(end -0.1778 0.2794)
						)
						(arc
							(start 0.1778 0.2794)
							(mid 0.249642 0.249642)
							(end 0.2794 0.1778)
						)
						(arc
							(start 0.2794 -0.1778)
							(mid 0.249642 -0.249642)
							(end 0.1778 -0.2794)
						)
					)
					(width 0)
					(fill yes)
				)
			)
		)
		(pad "2" smd custom
			(at 0 0.4445 180)
			(size 0.1397 0.1397)
			(layers "F.Cu" "F.Mask" "F.Paste")
			(net "SW_HDD_N14")
			(options
				(clearance outline)
				(anchor circle)
			)
			(primitives
				(gr_poly
					(pts
						(arc
							(start -0.1778 -0.2794)
							(mid -0.249642 -0.249642)
							(end -0.2794 -0.1778)
						)
						(arc
							(start -0.2794 0.1778)
							(mid -0.249642 0.249642)
							(end -0.1778 0.2794)
						)
						(arc
							(start 0.1778 0.2794)
							(mid 0.249642 0.249642)
							(end 0.2794 0.1778)
						)
						(arc
							(start 0.2794 -0.1778)
							(mid 0.249642 -0.249642)
							(end 0.1778 -0.2794)
						)
					)
					(width 0)
					(fill yes)
				)
			)
		)
	)
	(footprint ""
		(layer "F.Cu")
		(at 319.9892 -158.939992 90)
		(property "Reference" "VIA7"
			(at 0 0 90)
			(layer "F.SilkS")
			(hide yes)
			(effects
				(font
					(size 1.27 1.27)
				)
			)
		)
		(property "Value" "100OHM-8L-1D6MM-L18L16-GP"
			(at -3.7211 -4.5085 90)
			(unlocked yes)
			(layer "F.Fab")
			(hide yes)
			(effects
				(font
					(size 1.016 1.016)
					(thickness 0.1524)
				)
			)
		)
		(property "Device Type" "VIA-PCIE-4P-394076"
			(at -3.7211 -6.0325 90)
			(unlocked yes)
			(layer "F.Fab")
			(hide yes)
			(effects
				(font
					(size 1.016 1.016)
					(thickness 0.1524)
				)
			)
		)
		(duplicate_pad_numbers_are_jumpers no)
		(fp_rect
			(start -1.9685 0.381)
			(end 1.9685 -0.381)
			(stroke
				(width 0)
				(type default)
			)
			(fill no)
			(layer "F.CrtYd")
		)
		(fp_rect
			(start -1.9685 0.381)
			(end 1.9685 -0.381)
			(stroke
				(width 0)
				(type default)
			)
			(fill no)
			(layer "F.Fab")
		)
		(pad "1" thru_hole circle
			(at -1.5875 0 90)
			(size 0.508 0.508)
			(drill 0.254)
			(layers "*.Cu" "*.Mask")
			(remove_unused_layers no)
			(net "GND")
			(clearance 0.127)
			(thermal_gap 0.127)
		)
		(pad "2" thru_hole circle
			(at -0.5715 0 90)
			(size 0.508 0.508)
			(drill 0.254)
			(layers "*.Cu" "*.Mask")
			(remove_unused_layers no)
			(net "PHY_SCC_A_TO_DRV_A_18_DP")
			(clearance 0.127)
			(thermal_gap 0.127)
		)
		(pad "3" thru_hole circle
			(at 0.5715 0 90)
			(size 0.508 0.508)
			(drill 0.254)
			(layers "*.Cu" "*.Mask")
			(remove_unused_layers no)
			(net "PHY_SCC_A_TO_DRV_A_18_DN")
			(clearance 0.127)
			(thermal_gap 0.127)
		)
		(pad "4" thru_hole circle
			(at 1.5875 0 90)
			(size 0.508 0.508)
			(drill 0.254)
			(layers "*.Cu" "*.Mask")
			(remove_unused_layers no)
			(net "GND")
			(clearance 0.127)
			(thermal_gap 0.127)
		)
	)
	(footprint ""
		(layer "F.Cu")
		(at 259.3848 -280.0604)
		(property "Reference" "C33"
			(at 0 0 0)
			(layer "F.SilkS")
			(hide yes)
			(effects
				(font
					(size 1.27 1.27)
				)
			)
		)
		(property "Value" "SCD1U16V2KX-3GP"
			(at 1.1811 -2.7051 0)
			(unlocked yes)
			(layer "F.Fab")
			(hide yes)
			(effects
				(font
					(size 1.016 1.016)
					(thickness 0.1524)
				)
			)
		)
		(property "Device Type" "C402H22"
			(at 1.1811 -4.2291 0)
			(unlocked yes)
			(layer "F.Fab")
			(hide yes)
			(effects
				(font
					(size 1.016 1.016)
					(thickness 0.1524)
				)
			)
		)
		(duplicate_pad_numbers_are_jumpers no)
		(fp_rect
			(start -0.4318 0.9525)
			(end 0.4318 -0.9525)
			(stroke
				(width 0)
				(type default)
			)
			(fill no)
			(layer "F.CrtYd")
		)
		(fp_rect
			(start -0.4318 0.9525)
			(end 0.4318 -0.9525)
			(stroke
				(width 0)
				(type default)
			)
			(fill no)
			(layer "F.Fab")
		)
		(pad "1" smd custom
			(at 0 -0.4445)
			(size 0.1524 0.1524)
			(layers "F.Cu" "F.Mask" "F.Paste")
			(net "P3V3_STBY_A")
			(options
				(clearance outline)
				(anchor circle)
			)
			(primitives
				(gr_poly
					(pts
						(arc
							(start 0.3048 -0.2032)
							(mid 0.275042 -0.275042)
							(end 0.2032 -0.3048)
						)
						(arc
							(start -0.2032 -0.3048)
							(mid -0.275042 -0.275042)
							(end -0.3048 -0.2032)
						)
						(arc
							(start -0.3048 0.2032)
							(mid -0.275042 0.275042)
							(end -0.2032 0.3048)
						)
						(arc
							(start 0.2032 0.3048)
							(mid 0.275042 0.275042)
							(end 0.3048 0.2032)
						)
					)
					(width 0)
					(fill yes)
				)
			)
		)
		(pad "2" smd custom
			(at 0 0.4445)
			(size 0.1524 0.1524)
			(layers "F.Cu" "F.Mask" "F.Paste")
			(net "GND")
			(options
				(clearance outline)
				(anchor circle)
			)
			(primitives
				(gr_poly
					(pts
						(arc
							(start 0.3048 -0.2032)
							(mid 0.275042 -0.275042)
							(end 0.2032 -0.3048)
						)
						(arc
							(start -0.2032 -0.3048)
							(mid -0.275042 -0.275042)
							(end -0.3048 -0.2032)
						)
						(arc
							(start -0.3048 0.2032)
							(mid -0.275042 0.275042)
							(end -0.2032 0.3048)
						)
						(arc
							(start 0.2032 0.3048)
							(mid 0.275042 0.275042)
							(end 0.3048 0.2032)
						)
					)
					(width 0)
					(fill yes)
				)
			)
		)
	)
	(footprint ""
		(layer "F.Cu")
		(at 343.611962 -242.809776 180)
		(property "Reference" "Q234"
			(at 0 0 180)
			(layer "F.SilkS")
			(hide yes)
			(effects
				(font
					(size 1.27 1.27)
				)
			)
		)
		(property "Value" "2N7002K-2-GP"
			(at 0.127 -8.9662 180)
			(unlocked yes)
			(layer "F.Fab")
			(hide yes)
			(effects
				(font
					(size 1.016 1.016)
					(thickness 0.1524)
				)
			)
		)
		(property "Device Type" "SOT23DGS2D4H44"
			(at 0.127 -10.4902 180)
			(unlocked yes)
			(layer "F.Fab")
			(hide yes)
			(effects
				(font
					(size 1.016 1.016)
					(thickness 0.1524)
				)
			)
		)
		(duplicate_pad_numbers_are_jumpers no)
		(fp_line
			(start 1.651 1.778)
			(end 1.651 -1.778)
			(stroke
				(width 0.1524)
				(type default)
			)
			(layer "F.SilkS")
		)
		(fp_line
			(start 1.651 -1.778)
			(end -1.651 -1.778)
			(stroke
				(width 0.1524)
				(type default)
			)
			(layer "F.SilkS")
		)
		(fp_line
			(start -1.651 1.778)
			(end 1.651 1.778)
			(stroke
				(width 0.1524)
				(type default)
			)
			(layer "F.SilkS")
		)
		(fp_line
			(start -1.651 -1.778)
			(end -1.651 1.778)
			(stroke
				(width 0.1524)
				(type default)
			)
			(layer "F.SilkS")
		)
		(fp_poly
			(pts
				(xy -1.778 1.8796) (xy -1.778 -1.8796) (xy 1.778 -1.8796) (xy 1.778 1.8796)
			)
			(stroke
				(width 0)
				(type default)
			)
			(fill no)
			(layer "F.CrtYd")
		)
		(fp_poly
			(pts
				(xy -1.778 1.8796) (xy -1.778 -1.8796) (xy 1.778 -1.8796) (xy 1.778 1.8796)
			)
			(stroke
				(width 0)
				(type default)
			)
			(fill no)
			(layer "F.Fab")
		)
		(pad "D" smd custom
			(at 0 -0.9525 180)
			(size 0.1905 0.1905)
			(layers "F.Cu" "F.Mask" "F.Paste")
			(net "FLT_HDD7_N")
			(options
				(clearance outline)
				(anchor circle)
			)
			(primitives
				(gr_poly
					(pts
						(arc
							(start -0.1778 0.5715)
							(mid -0.321484 0.511984)
							(end -0.381 0.3683)
						)
						(arc
							(start -0.381 -0.3683)
							(mid -0.321484 -0.511984)
							(end -0.1778 -0.5715)
						)
						(arc
							(start 0.1778 -0.5715)
							(mid 0.321484 -0.511984)
							(end 0.381 -0.3683)
						)
						(arc
							(start 0.381 0.3683)
							(mid 0.321484 0.511984)
							(end 0.1778 0.5715)
						)
					)
					(width 0)
					(fill yes)
				)
			)
		)
		(pad "G" smd custom
			(at -0.98425 0.9525 180)
			(size 0.1905 0.1905)
			(layers "F.Cu" "F.Mask" "F.Paste")
			(net "DRIVE_A_7_FLT_LED")
			(options
				(clearance outline)
				(anchor circle)
			)
			(primitives
				(gr_poly
					(pts
						(arc
							(start -0.1778 0.5715)
							(mid -0.321484 0.511984)
							(end -0.381 0.3683)
						)
						(arc
							(start -0.381 -0.3683)
							(mid -0.321484 -0.511984)
							(end -0.1778 -0.5715)
						)
						(arc
							(start 0.1778 -0.5715)
							(mid 0.321484 -0.511984)
							(end 0.381 -0.3683)
						)
						(arc
							(start 0.381 0.3683)
							(mid 0.321484 0.511984)
							(end 0.1778 0.5715)
						)
					)
					(width 0)
					(fill yes)
				)
			)
		)
		(pad "S" smd custom
			(at 0.98425 0.9525 180)
			(size 0.1905 0.1905)
			(layers "F.Cu" "F.Mask" "F.Paste")
			(net "GND")
			(options
				(clearance outline)
				(anchor circle)
			)
			(primitives
				(gr_poly
					(pts
						(arc
							(start -0.1778 0.5715)
							(mid -0.321484 0.511984)
							(end -0.381 0.3683)
						)
						(arc
							(start -0.381 -0.3683)
							(mid -0.321484 -0.511984)
							(end -0.1778 -0.5715)
						)
						(arc
							(start 0.1778 -0.5715)
							(mid 0.321484 -0.511984)
							(end 0.381 -0.3683)
						)
						(arc
							(start 0.381 0.3683)
							(mid 0.321484 0.511984)
							(end 0.1778 0.5715)
						)
					)
					(width 0)
					(fill yes)
				)
			)
		)
	)
)
